FILE_TYPE=LIBRARY_PARTS;
primitive 'TPS54821','TPS54821_LCC';
  pin
    'BOOT':
      PIN_NUMBER='(13)';
      PIN_TYPE='ANALOG';
      NO_LOAD_CHECK='Both';
      NO_IO_CHECK='Both';
      NO_ASSERT_CHECK='TRUE';
      NO_DIR_CHECK='TRUE';
      ALLOW_CONNECT='TRUE';
    'COMP':
      PIN_NUMBER='(8)';
      BIDIRECTIONAL='TRUE';
      INPUT_LOAD='(-0.01,0.01)';
      OUTPUT_LOAD='(1.0,-1.0)';
    'EN':
      PIN_NUMBER='(10)';
      INPUT_LOAD='(-0.01,0.01)';
    'GND'<1>:
      PIN_NUMBER='(3)';
      PINUSE='GROUND';
      NO_LOAD_CHECK='Both';
      NO_IO_CHECK='Both';
      NO_ASSERT_CHECK='TRUE';
      NO_DIR_CHECK='TRUE';
      ALLOW_CONNECT='TRUE';
    'GND'<0>:
      PIN_NUMBER='(2)';
      PINUSE='GROUND';
      NO_LOAD_CHECK='Both';
      NO_IO_CHECK='Both';
      NO_ASSERT_CHECK='TRUE';
      NO_DIR_CHECK='TRUE';
      ALLOW_CONNECT='TRUE';
    'PH'<1>:
      PIN_NUMBER='(12)';
      OUTPUT_LOAD='(1.0,-1.0)';
    'PH'<0>:
      PIN_NUMBER='(11)';
      OUTPUT_LOAD='(1.0,-1.0)';
    'PVIN'<1>:
      PIN_NUMBER='(5)';
      INPUT_LOAD='(-0.01,0.01)';
    'PVIN'<0>:
      PIN_NUMBER='(4)';
      INPUT_LOAD='(-0.01,0.01)';
    'PWRGD':
      PIN_NUMBER='(14)';
      OUTPUT_LOAD='(1.0,-1.0)';
    'RT_CLK':
      PIN_NUMBER='(1)';
      INPUT_LOAD='(-0.01,0.01)';
    'SS_TR':
      PIN_NUMBER='(9)';
      INPUT_LOAD='(-0.01,0.01)';
    'THPAD':
      PIN_NUMBER='(15)';
      PINUSE='GROUND';
      NO_LOAD_CHECK='Both';
      NO_IO_CHECK='Both';
      NO_ASSERT_CHECK='TRUE';
      NO_DIR_CHECK='TRUE';
      ALLOW_CONNECT='TRUE';
    'VIN':
      PIN_NUMBER='(6)';
      INPUT_LOAD='(-0.01,0.01)';
    'VSENSE':
      PIN_NUMBER='(7)';
      INPUT_LOAD='(-0.01,0.01)';
  end_pin;
  body
    PART_NAME='TPS54821';
    PHYS_DES_PREFIX='EU';
  end_body;
end_primitive;

END.
